(kicad_pcb
	(version 20221018)
	(generator pcbnew)
	(general
    (thickness 1.586)
  )
	(paper "A4")
	(title_block
    (date "2024-03-26")
    (rev "1.1.3")
		(comment 9 "footprints 61-68 of 146")
	)
	(layers
    (0 "F.Cu" signal)
    (1 "In1.Cu" power)
    (2 "In2.Cu" power)
    (31 "B.Cu" signal)
    (32 "B.Adhes" user "B.Adhesive")
    (33 "F.Adhes" user "F.Adhesive")
    (34 "B.Paste" user)
    (35 "F.Paste" user)
    (36 "B.SilkS" user "B.Silkscreen")
    (37 "F.SilkS" user "F.Silkscreen")
    (38 "B.Mask" user)
    (39 "F.Mask" user)
    (40 "Dwgs.User" user "User.Drawings")
    (41 "Cmts.User" user "User.Comments")
    (42 "Eco1.User" user "User.Eco1")
    (43 "Eco2.User" user "User.Eco2")
    (44 "Edge.Cuts" user)
    (45 "Margin" user)
    (46 "B.CrtYd" user "B.Courtyard")
    (47 "F.CrtYd" user "F.Courtyard")
    (48 "B.Fab" user)
    (49 "F.Fab" user)
  )
	(footprint "scalenode-cm4-baseboard-footprints:CONV_PDQE30-Q48-S5-D" locked (layer "F.Cu")
    (at 117.09 73.05)
    (property "Author" "Antmicro")
    (property "License" "Apache-2.0")
    (property "MPN" "PDQE30-Q48-S5-D")
    (property "Manufacturer" "CUI Inc")
    (property "Sheetfile" "poe.kicad_sch")
    (property "Sheetname" "PoE")
    (property "ki_description" "DC-DC CONVERTER, 48VDC input, 5VDC nom isolated output w/ trim option, 30W, 270kHz PWM mode")
    (property "ki_keywords" "dc converter step down 5v 48v isolated 30W poe")
    (attr through_hole)
    (fp_text reference "U7" (at -2.74 -3.81) (layer "F.SilkS")
        (effects (font (size 0.7 0.7) (thickness 0.15)) (justify left bottom))
    )
    (fp_text value "PDQE30-Q48-S5-D" (at 10.32 24.312) (layer "F.Fab")
        (effects (font (size 0.7 0.7) (thickness 0.15)) (justify left bottom))
    )
    (fp_text user "${REFERENCE}" (at -3.912 28.711) (layer "F.Fab") hide
        (effects (font (size 0.7 0.7) (thickness 0.15)) (justify left bottom))
    )
    (fp_text user "License: Apache-2.0" (at -3.912 27.51) (layer "F.Fab") hide
        (effects (font (size 0.7 0.7) (thickness 0.15)) (justify left bottom))
    )
    (fp_text user "Author: Antmicro" (at -3.912 26.312) (layer "F.Fab") hide
        (effects (font (size 0.7 0.7) (thickness 0.15)) (justify left bottom))
    )
    (fp_line (start -2.54 -2.54) (end 22.859 -2.54)
      (stroke (width 0.15) (type solid)) (layer "F.SilkS"))
    (fp_line (start -2.54 22.859) (end -2.54 -2.54)
      (stroke (width 0.15) (type solid)) (layer "F.SilkS"))
    (fp_line (start 22.859 -2.54) (end 22.859 22.859)
      (stroke (width 0.15) (type solid)) (layer "F.SilkS"))
    (fp_line (start 22.859 22.859) (end -2.54 22.859)
      (stroke (width 0.15) (type solid)) (layer "F.SilkS"))
    (fp_circle (center -2.921 0) (end -2.82 0)
      (stroke (width 0.15) (type solid)) (fill none) (layer "F.SilkS"))
    (fp_circle (center 0 -3.84) (end 0.05 -3.84)
      (stroke (width 0.15) (type solid)) (fill solid) (layer "F.SilkS"))
    (fp_circle (center 0 -3.84) (end 0.05 -3.84)
      (stroke (width 0.15) (type solid)) (fill solid) (layer "F.SilkS"))
    (fp_rect (start -2.667 -2.667) (end 22.987 22.987)
      (stroke (width 0.05) (type solid)) (fill none) (layer "F.CrtYd"))
    (fp_line (start -2.54 -2.54) (end 22.859 -2.54)
      (stroke (width 0.15) (type solid)) (layer "F.Fab"))
    (fp_line (start -2.54 22.859) (end -2.54 -2.54)
      (stroke (width 0.15) (type solid)) (layer "F.Fab"))
    (fp_line (start 22.859 -2.54) (end 22.859 22.859)
      (stroke (width 0.15) (type solid)) (layer "F.Fab"))
    (fp_line (start 22.859 22.859) (end -2.54 22.859)
      (stroke (width 0.15) (type solid)) (layer "F.Fab"))
    (fp_circle (center -2.921 0) (end -2.82 0)
      (stroke (width 0.15) (type solid)) (fill none) (layer "F.Fab"))
    (pad "1" thru_hole rect locked (at 0 0) (size 2.25 2.25) (drill 1.5) (layers "*.Cu" "*.Mask")
      (net 34 "/PoE/POE_ACTIVE") (pinfunction "CTRL") (pintype "input"))
    (pad "2" thru_hole circle locked (at 0 7.618) (size 2.25 2.25) (drill 1.5) (layers "*.Cu" "*.Mask")
      (net 4 "GNDD") (pinfunction "GND") (pintype "power_in"))
    (pad "3" thru_hole circle locked (at 0 12.698) (size 2.25 2.25) (drill 1.5) (layers "*.Cu" "*.Mask")
      (net 6 "/PoE/VDD_POE_IN") (pinfunction "V_{IN}") (pintype "power_in"))
    (pad "4" thru_hole circle locked (at 20.318 20.318) (size 2.25 2.25) (drill 1.5) (layers "*.Cu" "*.Mask")
      (net 13 "/PoE/VO5V") (pinfunction "V_{O}") (pintype "power_out"))
    (pad "5" thru_hole circle locked (at 20.318 10.159) (size 2.25 2.25) (drill 1.5) (layers "*.Cu" "*.Mask")
      (net 277 "unconnected-(U7-TRIM-Pad5)") (pinfunction "TRIM") (pintype "passive+no_connect"))
    (pad "6" thru_hole circle locked (at 20.318 0) (size 2.25 2.25) (drill 1.5) (layers "*.Cu" "*.Mask")
      (net 11 "GND") (pinfunction "0V") (pintype "power_out"))
  )
	(footprint "scalenode-cm4-baseboard-footprints:R_0402_1005Metric" (layer "F.Cu")
    (at 86.885 92.2)
    (descr "Resistor SMD 0402")
    (tags "resistor SMD 0402")
    (property "Author" "Antmicro")
    (property "DNP" "DNP")
    (property "License" "Apache-2.0")
    (property "MPN" "CR0402-FX-63R4GLF")
    (property "Manufacturer" "Bourns")
    (property "Sheetfile" "poe.kicad_sch")
    (property "Sheetname" "PoE")
    (property "Tolerance" "1%")
    (property "Val" "63R4")
    (property "dnp" "")
    (property "exclude_from_bom" "")
    (property "ki_description" "63R4 resistor in 0402 package with 1% tolerance")
    (attr exclude_from_pos_files exclude_from_bom)
    (fp_text reference "R20" (at -1.085 1.375) (layer "F.SilkS")
        (effects (font (size 0.7 0.7) (thickness 0.15)) (justify left bottom))
    )
    (fp_text value "R_63R4_0402" (at 0 1.4) (layer "F.Fab")
        (effects (font (size 0.7 0.7) (thickness 0.15)) (justify left bottom))
    )
    (fp_text user "Author: Antmicro" (at -0.95 4.169) (layer "F.Fab") hide
        (effects (font (size 0.7 0.7) (thickness 0.15)) (justify left bottom))
    )
    (fp_text user "${REFERENCE}" (at -0.95 3.168) (layer "F.Fab") hide
        (effects (font (size 0.7 0.7) (thickness 0.15)) (justify left bottom))
    )
    (fp_text user "License: Apache-2.0" (at -0.95 5.169) (layer "F.Fab") hide
        (effects (font (size 0.7 0.7) (thickness 0.15)) (justify left bottom))
    )
    (fp_rect (start -0.95 -0.48) (end 0.95 0.48)
      (stroke (width 0.05) (type solid)) (fill none) (layer "F.CrtYd"))
    (fp_rect (start -0.5 -0.25) (end 0.5 0.25)
      (stroke (width 0.15) (type solid)) (fill none) (layer "F.Fab"))
    (pad "1" smd roundrect (at -0.485 0) (size 0.59 0.64) (layers "F.Cu" "F.Paste" "F.Mask") (roundrect_rratio 0.25)
      (net 254 "Net-(U3-CLSA)") (pintype "passive"))
    (pad "2" smd roundrect (at 0.485 0) (size 0.59 0.64) (layers "F.Cu" "F.Paste" "F.Mask") (roundrect_rratio 0.25)
      (net 5 "VSS") (pintype "passive"))
  )
	(footprint "scalenode-cm4-baseboard-footprints:R_0603_1608Metric" (layer "F.Cu")
    (at 79.15 77.94)
    (descr "Resistor SMD 0603")
    (tags "resistor SMD 0603")
    (property "Author" "Antmicro")
    (property "License" "Apache-2.0")
    (property "MPN" "CR0603-FX-2700ELF")
    (property "Manufacturer" "Bourns")
    (property "Sheetfile" "nvme-ssd.kicad_sch")
    (property "Sheetname" "NVMe SSD")
    (property "Tolerance" "1%")
    (property "Val" "270R")
    (property "ki_description" "270R resistor in 0603 package with 1% tolerance")
    (attr smd)
    (fp_text reference "R2" (at -1.39 1.55) (layer "F.SilkS")
        (effects (font (size 0.7 0.7) (thickness 0.15)) (justify left bottom))
    )
    (fp_text value "R_270R_0603" (at 0 1.6) (layer "F.Fab")
        (effects (font (size 0.7 0.7) (thickness 0.15)) (justify left bottom))
    )
    (fp_text user "${REFERENCE}" (at -1.25 3.898) (layer "F.Fab") hide
        (effects (font (size 0.7 0.7) (thickness 0.15)) (justify left bottom))
    )
    (fp_text user "Author: Antmicro" (at -1.25 4.9) (layer "F.Fab") hide
        (effects (font (size 0.7 0.7) (thickness 0.15)) (justify left bottom))
    )
    (fp_text user "License: Apache-2.0" (at -1.25 5.9) (layer "F.Fab") hide
        (effects (font (size 0.7 0.7) (thickness 0.15)) (justify left bottom))
    )
    (fp_line (start -0.3 -0.3) (end 0.3 -0.3)
      (stroke (width 0.15) (type solid)) (layer "F.SilkS"))
    (fp_line (start -0.3 0.3) (end 0.3 0.3)
      (stroke (width 0.15) (type solid)) (layer "F.SilkS"))
    (fp_rect (start -1.25 -0.7) (end 1.25 0.7)
      (stroke (width 0.05) (type solid)) (fill none) (layer "F.CrtYd"))
    (fp_rect (start -0.8 -0.4) (end 0.8 0.4)
      (stroke (width 0.15) (type solid)) (fill none) (layer "F.Fab"))
    (pad "1" smd roundrect (at -0.7 0) (size 0.6 0.8) (layers "F.Cu" "F.Paste" "F.Mask") (roundrect_rratio 0.2)
      (net 188 "Net-(D1-Pad1)") (pintype "passive"))
    (pad "2" smd roundrect (at 0.7 0) (size 0.6 0.8) (layers "F.Cu" "F.Paste" "F.Mask") (roundrect_rratio 0.2)
      (net 170 "3V3_SSD") (pintype "passive"))
  )
	(footprint "scalenode-cm4-baseboard-footprints:TP_SMD_1mm" (layer "F.Cu")
    (at 98.916 89.402)
    (property "Author" "Antmicro")
    (property "License" "Apache-2.0")
    (property "MPN" "")
    (property "Manufacturer" "")
    (property "Sheetfile" "poe.kicad_sch")
    (property "Sheetname" "PoE")
    (property "ki_description" "Test Point 1mm")
    (attr exclude_from_pos_files)
    (fp_text reference "TP3" (at -0.866 -0.802) (layer "F.SilkS")
        (effects (font (size 0.7 0.7) (thickness 0.15)) (justify left bottom))
    )
    (fp_text value "TP_1mm_SMD" (at 0 1.4) (layer "F.Fab")
        (effects (font (size 0.7 0.7) (thickness 0.15)) (justify left bottom))
    )
    (fp_text user "Author: Antmicro" (at -0.5 4) (layer "F.Fab") hide
        (effects (font (size 0.7 0.7) (thickness 0.15)) (justify left bottom))
    )
    (fp_text user "${REFERENCE}" (at -0.5 2.8) (layer "F.Fab") hide
        (effects (font (size 0.7 0.7) (thickness 0.15)) (justify left bottom))
    )
    (fp_text user "License: Apache-2.0" (at -0.5 5.2) (layer "F.Fab") hide
        (effects (font (size 0.7 0.7) (thickness 0.15)) (justify left bottom))
    )
    (pad "1" smd circle (at 0 0) (size 1 1) (layers "F.Cu" "F.Mask")
      (net 6 "/PoE/VDD_POE_IN") (pinfunction "1") (pintype "passive"))
  )
	(footprint "scalenode-cm4-baseboard-footprints:TP_SMD_0.75mm" (layer "F.Cu")
    (at 96.2 90.7)
    (property "Author" "Antmicro")
    (property "License" "Apache-2.0")
    (property "MPN" "")
    (property "Manufacturer" "")
    (property "Sheetfile" "poe.kicad_sch")
    (property "Sheetname" "PoE")
    (property "ki_description" "Test Point 0.75mm")
    (attr exclude_from_pos_files)
    (fp_text reference "TP8" (at -0.925 1.375) (layer "F.SilkS")
        (effects (font (size 0.7 0.7) (thickness 0.15)) (justify left bottom))
    )
    (fp_text value "TP_0.75mm_SMD" (at 0 1.2) (layer "F.Fab")
        (effects (font (size 0.7 0.7) (thickness 0.15)) (justify left bottom))
    )
    (fp_text user "${REFERENCE}" (at -0.4 2.7) (layer "F.Fab") hide
        (effects (font (size 0.7 0.7) (thickness 0.15)) (justify left bottom))
    )
    (fp_text user "License: Apache-2.0" (at -0.4 5.101) (layer "F.Fab") hide
        (effects (font (size 0.7 0.7) (thickness 0.15)) (justify left bottom))
    )
    (fp_text user "Author: Antmicro" (at -0.4 3.901) (layer "F.Fab") hide
        (effects (font (size 0.7 0.7) (thickness 0.15)) (justify left bottom))
    )
    (pad "1" smd circle (at 0 0) (size 0.75 0.75) (layers "F.Cu" "F.Mask")
      (net 271 "Net-(U3-VC_OUT)") (pinfunction "1") (pintype "passive"))
  )
	(footprint "scalenode-cm4-baseboard-footprints:R_0402_1005Metric" (layer "F.Cu")
    (at 91 87.1 90)
    (descr "Resistor SMD 0402")
    (tags "resistor SMD 0402")
    (property "Author" "Antmicro")
    (property "DNP" "DNP")
    (property "License" "Apache-2.0")
    (property "MPN" "CR0402-FX-1002GLF")
    (property "Manufacturer" "Bourns")
    (property "Sheetfile" "poe.kicad_sch")
    (property "Sheetname" "PoE")
    (property "Tolerance" "1%")
    (property "Val" "10k")
    (property "dnp" "")
    (property "exclude_from_bom" "")
    (property "ki_description" "10k resistor in 0402 package with 1% tolerance")
    (attr exclude_from_pos_files exclude_from_bom)
    (fp_text reference "R41" (at 1 0.325 90) (layer "F.SilkS")
        (effects (font (size 0.7 0.7) (thickness 0.15)) (justify left bottom))
    )
    (fp_text value "R_10k_0402" (at 0 1.4 90) (layer "F.Fab")
        (effects (font (size 0.7 0.7) (thickness 0.15)) (justify left bottom))
    )
    (fp_text user "Author: Antmicro" (at -0.95 4.169 90) (layer "F.Fab") hide
        (effects (font (size 0.7 0.7) (thickness 0.15)) (justify left bottom))
    )
    (fp_text user "${REFERENCE}" (at -0.95 3.168 90) (layer "F.Fab") hide
        (effects (font (size 0.7 0.7) (thickness 0.15)) (justify left bottom))
    )
    (fp_text user "License: Apache-2.0" (at -0.95 5.169 90) (layer "F.Fab") hide
        (effects (font (size 0.7 0.7) (thickness 0.15)) (justify left bottom))
    )
    (fp_rect (start -0.95 -0.48) (end 0.95 0.48)
      (stroke (width 0.05) (type solid)) (fill none) (layer "F.CrtYd"))
    (fp_rect (start -0.5 -0.25) (end 0.5 0.25)
      (stroke (width 0.15) (type solid)) (fill none) (layer "F.Fab"))
    (pad "1" smd roundrect (at -0.485 0 90) (size 0.59 0.64) (layers "F.Cu" "F.Paste" "F.Mask") (roundrect_rratio 0.25)
      (net 263 "Net-(U3-~{BT})") (pintype "passive"))
    (pad "2" smd roundrect (at 0.485 0 90) (size 0.59 0.64) (layers "F.Cu" "F.Paste" "F.Mask") (roundrect_rratio 0.25)
      (net 6 "/PoE/VDD_POE_IN") (pintype "passive"))
  )
	(footprint "scalenode-cm4-baseboard-footprints:R_0402_1005Metric" (layer "F.Cu")
    (at 85.9 90.85)
    (descr "Resistor SMD 0402")
    (tags "resistor SMD 0402")
    (property "Author" "Antmicro")
    (property "DNP" "DNP")
    (property "License" "Apache-2.0")
    (property "MPN" "CR0402-FX-2492GLF")
    (property "Manufacturer" "Bourns")
    (property "Sheetfile" "poe.kicad_sch")
    (property "Sheetname" "PoE")
    (property "Tolerance" "1%")
    (property "Val" "24k9")
    (property "dnp" "")
    (property "exclude_from_bom" "")
    (property "ki_description" "24k9 resistor in 0402 package with 1% tolerance")
    (attr exclude_from_pos_files exclude_from_bom)
    (fp_text reference "R36" (at -1.05 -0.65) (layer "F.SilkS")
        (effects (font (size 0.7 0.7) (thickness 0.15)) (justify left bottom))
    )
    (fp_text value "R_24k9_0402" (at 0 1.4) (layer "F.Fab")
        (effects (font (size 0.7 0.7) (thickness 0.15)) (justify left bottom))
    )
    (fp_text user "License: Apache-2.0" (at -0.95 5.169) (layer "F.Fab") hide
        (effects (font (size 0.7 0.7) (thickness 0.15)) (justify left bottom))
    )
    (fp_text user "Author: Antmicro" (at -0.95 4.169) (layer "F.Fab") hide
        (effects (font (size 0.7 0.7) (thickness 0.15)) (justify left bottom))
    )
    (fp_text user "${REFERENCE}" (at -0.95 3.168) (layer "F.Fab") hide
        (effects (font (size 0.7 0.7) (thickness 0.15)) (justify left bottom))
    )
    (fp_rect (start -0.95 -0.48) (end 0.95 0.48)
      (stroke (width 0.05) (type solid)) (fill none) (layer "F.CrtYd"))
    (fp_rect (start -0.5 -0.25) (end 0.5 0.25)
      (stroke (width 0.15) (type solid)) (fill none) (layer "F.Fab"))
    (pad "1" smd roundrect (at -0.485 0) (size 0.59 0.64) (layers "F.Cu" "F.Paste" "F.Mask") (roundrect_rratio 0.25)
      (net 6 "/PoE/VDD_POE_IN") (pintype "passive"))
    (pad "2" smd roundrect (at 0.485 0) (size 0.59 0.64) (layers "F.Cu" "F.Paste" "F.Mask") (roundrect_rratio 0.25)
      (net 258 "Net-(U3-DEN)") (pintype "passive"))
  )
	(footprint "scalenode-cm4-baseboard-footprints:Conn_JST_XH_1x2_B2B-XH-A-LF-SN" (layer "F.Cu")
    (at 130.7 60.2 180)
    (descr "http://www.jst-mfg.com/product/pdf/eng/eXH.pdf")
    (property "Author" "Antmicro")
    (property "License" "Apache-2.0")
    (property "MPN" "B2B-XH-A(LF)(SN)")
    (property "Manufacturer" "JST Automotive Connectors")
    (property "Sheetfile" "poe.kicad_sch")
    (property "Sheetname" "PoE")
    (property "ki_description" "Rectangular connector, header")
    (property "ki_keywords" "CONNECTOR, THT")
    (attr through_hole)
    (fp_text reference "J1" (at 1.8 -4 180) (layer "F.SilkS")
        (effects (font (size 0.7 0.7) (thickness 0.15)) (justify left bottom))
    )
    (fp_text value "JST_XH_1x2_B2B-XH-A-LF-SN" (at -0.225 -0.4 180) (layer "F.Fab")
        (effects (font (size 0.7 0.7) (thickness 0.15)) (justify left bottom))
    )
    (fp_text user "License: Apache-2.0" (at -2.702 8.81 180) (layer "F.Fab") hide
        (effects (font (size 0.7 0.7) (thickness 0.15)) (justify left bottom))
    )
    (fp_text user "${REFERENCE}" (at -2.702 6.41 180) (layer "F.Fab") hide
        (effects (font (size 0.7 0.7) (thickness 0.15)) (justify left bottom))
    )
    (fp_text user "Author: Antmicro" (at -2.702 7.61 180) (layer "F.Fab") hide
        (effects (font (size 0.7 0.7) (thickness 0.15)) (justify left bottom))
    )
    (fp_line (start -2.601 -3) (end -2.601 -2.5)
      (stroke (width 0.15) (type solid)) (layer "F.SilkS"))
    (fp_line (start -2.601 -3) (end -2.101 -3)
      (stroke (width 0.15) (type solid)) (layer "F.SilkS"))
    (fp_line (start -2.601 2.999) (end -2.601 2.499)
      (stroke (width 0.15) (type solid)) (layer "F.SilkS"))
    (fp_line (start -2.601 2.999) (end -2.101 2.999)
      (stroke (width 0.15) (type solid)) (layer "F.SilkS"))
    (fp_line (start 5.08 -3) (end 4.58 -3)
      (stroke (width 0.15) (type solid)) (layer "F.SilkS"))
    (fp_line (start 5.08 -3) (end 5.08 -2.5)
      (stroke (width 0.15) (type solid)) (layer "F.SilkS"))
    (fp_line (start 5.08 2.999) (end 4.58 2.999)
      (stroke (width 0.15) (type solid)) (layer "F.SilkS"))
    (fp_line (start 5.08 2.999) (end 5.08 2.499)
      (stroke (width 0.15) (type solid)) (layer "F.SilkS"))
    (fp_circle (center -3.252 0) (end -3.202 0)
      (stroke (width 0.15) (type solid)) (fill solid) (layer "F.SilkS"))
    (fp_line (start -2.71 -3.13) (end -2.71 3.12)
      (stroke (width 0.05) (type solid)) (layer "F.CrtYd"))
    (fp_line (start 5.1816 -3.13) (end -2.71 -3.13)
      (stroke (width 0.05) (type solid)) (layer "F.CrtYd"))
    (fp_line (start 5.1816 3.12) (end -2.71 3.12)
      (stroke (width 0.05) (type solid)) (layer "F.CrtYd"))
    (fp_line (start 5.1816 3.12) (end 5.1816 -3.13)
      (stroke (width 0.05) (type solid)) (layer "F.CrtYd"))
    (pad "1" thru_hole circle (at 0 0 180) (size 2.1 2.1) (drill 1.1) (layers "*.Cu" "*.Mask")
      (net 12 "VCC5V0") (pintype "passive"))
    (pad "2" thru_hole circle (at 2.499 0 180) (size 2.1 2.1) (drill 1.1) (layers "*.Cu" "*.Mask")
      (net 11 "GND") (pintype "passive"))
  )
)
